# T6G (Grand Teton) — schematic netlist excerpt (pin names and nets, part order shuffled) for the footprints in the layout excerpt that follows; sources: Cadence DE-HDL packaged netlist, KiCad conversion of 04192023_DAF0TMB3IC0_F0TG_MB_C_brd_V02_OCP.brd

C467  Q_CAP  1000PF 50V 5% EMPTY  pkg 0402  page 193 : A = PWRGD_PVDDCR_CPU0_P0_R ; B = GND
PC865  Q_CAP  22UF 4V 20% X6S  pkg C0805  page 269 : A = P1V8_AUX ; B = GND
R301  Q_RES  1K 1% CHIP  pkg 0402LF  page 96 : A = PWRGD_CHK_CPU0_DIMM ; B = PWRGD_CHGL_CPU0

(kicad_pcb
	(version 20260206)
	(generator "pcbnew")
	(generator_version "10.0")
	(general
		(thickness 1.6)
		(legacy_teardrops no)
	)
	(paper "A4")
	(title_block
		(title "04192023_DAF0TMB3IC0_F0TG_MB_C_brd_V02_OCP.brd")
		(comment 1 "Grand Teton / footprints 7208-7210 of 8354")
	)
	(layers
		(0 "F.Cu" signal "TOP")
		(4 "In1.Cu" signal "GND")
		(6 "In2.Cu" signal "IN1")
		(8 "In3.Cu" signal "GND1")
		(10 "In4.Cu" signal "IN2")
		(12 "In5.Cu" signal "GND2")
		(14 "In6.Cu" signal "IN3")
		(16 "In7.Cu" signal "GND3")
		(18 "In8.Cu" signal "VCC")
		(20 "In9.Cu" signal "VCC1")
		(22 "In10.Cu" signal "GND4")
		(24 "In11.Cu" signal "IN4")
		(26 "In12.Cu" signal "GND5")
		(28 "In13.Cu" signal "IN5")
		(30 "In14.Cu" signal "GND6")
		(32 "In15.Cu" signal "IN6")
		(34 "In16.Cu" signal "GND7")
		(2 "B.Cu" signal "BOTTOM")
		(9 "F.Adhes" user "F.Adhesive")
		(11 "B.Adhes" user "B.Adhesive")
		(13 "F.Paste" user "Package Geometry/Pastemask Top")
		(15 "B.Paste" user "Package Geometry/Pastemask Bottom")
		(5 "F.SilkS" user "Ref Des/Silkscreen Top")
		(7 "B.SilkS" user "Ref Des/Silkscreen Bottom")
		(1 "F.Mask" user "Board Geometry/Soldermask Top")
		(3 "B.Mask" user "Board Geometry/Soldermask Bottom")
		(17 "Dwgs.User" user "User.Drawings")
		(19 "Cmts.User" user "User.Comments")
		(21 "Eco1.User" user "User.Eco1")
		(23 "Eco2.User" user "User.Eco2")
		(25 "Edge.Cuts" user "Board Geometry/Outline")
		(27 "Margin" user)
		(31 "F.CrtYd" user "Package Geometry/Place Bound Top")
		(29 "B.CrtYd" user "Package Geometry/Place Bound Bottom")
		(35 "F.Fab" user "Ref Des/Assembly Top")
		(33 "B.Fab" user "Ref Des/Assembly Bottom")
	)
	(footprint ""
		(layer "B.Cu")
		(at 152.202642 -78.76921)
		(property "Reference" "PC865"
			(at 0 0 0)
			(layer "B.SilkS")
			(hide yes)
			(effects
				(font
					(size 1.27 1.27)
				)
				(justify mirror)
			)
		)
		(property "Value" ""
			(at 0 0 0)
			(layer "B.Fab")
			(effects
				(font
					(size 1.27 1.27)
				)
				(justify mirror)
			)
		)
		(duplicate_pad_numbers_are_jumpers no)
		(fp_line
			(start -1.524 -0.762)
			(end -1.524 0.762)
			(stroke
				(width 0.1524)
				(type default)
			)
			(layer "B.SilkS")
		)
		(fp_line
			(start -1.524 0.762)
			(end 1.524 0.762)
			(stroke
				(width 0.1524)
				(type default)
			)
			(layer "B.SilkS")
		)
		(fp_line
			(start 1.524 -0.762)
			(end -1.524 -0.762)
			(stroke
				(width 0.1524)
				(type default)
			)
			(layer "B.SilkS")
		)
		(fp_line
			(start 1.524 0.762)
			(end 1.524 -0.762)
			(stroke
				(width 0.1524)
				(type default)
			)
			(layer "B.SilkS")
		)
		(fp_line
			(start -1.1049 -0.724916)
			(end 1.1049 -0.724916)
			(stroke
				(width 0.1)
				(type default)
			)
			(layer "B.Fab")
		)
		(fp_line
			(start -1.1049 0.724916)
			(end -1.1049 -0.724916)
			(stroke
				(width 0.1)
				(type default)
			)
			(layer "B.Fab")
		)
		(fp_line
			(start 1.1049 -0.724916)
			(end 1.1049 0.724916)
			(stroke
				(width 0.1)
				(type default)
			)
			(layer "B.Fab")
		)
		(fp_line
			(start 1.1049 0.724916)
			(end -1.1049 0.724916)
			(stroke
				(width 0.1)
				(type default)
			)
			(layer "B.Fab")
		)
		(pad "1" smd rect
			(at 0.889 0)
			(size 1.016 1.27)
			(layers "B.Cu" "B.Mask" "B.Paste")
			(net "P1V8_AUX")
		)
		(pad "2" smd rect
			(at -0.889 0)
			(size 1.016 1.27)
			(layers "B.Cu" "B.Mask" "B.Paste")
			(net "GND")
		)
	)
	(footprint ""
		(layer "B.Cu")
		(at 442.290454 -191.20231 180)
		(property "Reference" "R301"
			(at 0 0 0)
			(layer "B.SilkS")
			(hide yes)
			(effects
				(font
					(size 1.27 1.27)
				)
				(justify mirror)
			)
		)
		(property "Value" ""
			(at 0 0 0)
			(layer "B.Fab")
			(effects
				(font
					(size 1.27 1.27)
				)
				(justify mirror)
			)
		)
		(duplicate_pad_numbers_are_jumpers no)
		(fp_line
			(start 0.7874 0.4064)
			(end 0.7874 -0.4064)
			(stroke
				(width 0.1524)
				(type default)
			)
			(layer "B.SilkS")
		)
		(fp_line
			(start 0.7874 -0.4064)
			(end -0.7874 -0.4064)
			(stroke
				(width 0.1524)
				(type default)
			)
			(layer "B.SilkS")
		)
		(fp_line
			(start -0.7874 0.4064)
			(end 0.7874 0.4064)
			(stroke
				(width 0.1524)
				(type default)
			)
			(layer "B.SilkS")
		)
		(fp_line
			(start -0.7874 -0.4064)
			(end -0.7874 0.4064)
			(stroke
				(width 0.1524)
				(type default)
			)
			(layer "B.SilkS")
		)
		(fp_line
			(start 0.67945 0.3048)
			(end 0.67945 -0.305054)
			(stroke
				(width 0.1)
				(type default)
			)
			(layer "B.Fab")
		)
		(fp_line
			(start 0.67945 -0.305054)
			(end 0.12065 -0.305054)
			(stroke
				(width 0.1)
				(type default)
			)
			(layer "B.Fab")
		)
		(fp_line
			(start 0.12065 0.3048)
			(end 0.67945 0.3048)
			(stroke
				(width 0.1)
				(type default)
			)
			(layer "B.Fab")
		)
		(fp_line
			(start 0.12065 0.2794)
			(end 0.12065 0.3048)
			(stroke
				(width 0.1)
				(type default)
			)
			(layer "B.Fab")
		)
		(fp_line
			(start 0.12065 -0.2794)
			(end -0.12065 -0.2794)
			(stroke
				(width 0.1)
				(type default)
			)
			(layer "B.Fab")
		)
		(fp_line
			(start 0.12065 -0.305054)
			(end 0.12065 -0.2794)
			(stroke
				(width 0.1)
				(type default)
			)
			(layer "B.Fab")
		)
		(fp_line
			(start -0.120396 0.3048)
			(end -0.120396 0.2794)
			(stroke
				(width 0.1)
				(type default)
			)
			(layer "B.Fab")
		)
		(fp_line
			(start -0.120396 0.2794)
			(end 0.12065 0.2794)
			(stroke
				(width 0.1)
				(type default)
			)
			(layer "B.Fab")
		)
		(fp_line
			(start -0.12065 -0.2794)
			(end -0.12065 -0.3048)
			(stroke
				(width 0.1)
				(type default)
			)
			(layer "B.Fab")
		)
		(fp_line
			(start -0.12065 -0.3048)
			(end -0.67945 -0.3048)
			(stroke
				(width 0.1)
				(type default)
			)
			(layer "B.Fab")
		)
		(fp_line
			(start -0.67945 0.3048)
			(end -0.120396 0.3048)
			(stroke
				(width 0.1)
				(type default)
			)
			(layer "B.Fab")
		)
		(fp_line
			(start -0.67945 -0.3048)
			(end -0.67945 0.3048)
			(stroke
				(width 0.1)
				(type default)
			)
			(layer "B.Fab")
		)
		(pad "1" smd circle
			(at 0.40005 0)
			(size 0 0)
			(layers "B.Cu" "B.Mask" "B.Paste")
			(net "PWRGD_CHK_CPU0_DIMM")
		)
		(pad "2" smd circle
			(at -0.40005 0)
			(size 0 0)
			(layers "B.Cu" "B.Mask" "B.Paste")
			(net "PWRGD_CHGL_CPU0")
		)
	)
	(footprint ""
		(layer "B.Cu")
		(at 372.937278 -139.440158)
		(property "Reference" "C467"
			(at 0 0 0)
			(layer "B.SilkS")
			(hide yes)
			(effects
				(font
					(size 1.27 1.27)
				)
				(justify mirror)
			)
		)
		(property "Value" ""
			(at 0 0 0)
			(layer "B.Fab")
			(effects
				(font
					(size 1.27 1.27)
				)
				(justify mirror)
			)
		)
		(duplicate_pad_numbers_are_jumpers no)
		(fp_line
			(start -0.7874 -0.4064)
			(end -0.7874 0.4064)
			(stroke
				(width 0.1524)
				(type default)
			)
			(layer "B.SilkS")
		)
		(fp_line
			(start -0.7874 0.4064)
			(end 0.7874 0.4064)
			(stroke
				(width 0.1524)
				(type default)
			)
			(layer "B.SilkS")
		)
		(fp_line
			(start 0.7874 -0.4064)
			(end -0.7874 -0.4064)
			(stroke
				(width 0.1524)
				(type default)
			)
			(layer "B.SilkS")
		)
		(fp_line
			(start 0.7874 0.4064)
			(end 0.7874 -0.4064)
			(stroke
				(width 0.1524)
				(type default)
			)
			(layer "B.SilkS")
		)
		(fp_line
			(start -0.67945 -0.3048)
			(end -0.67945 0.3048)
			(stroke
				(width 0.1)
				(type default)
			)
			(layer "B.Fab")
		)
		(fp_line
			(start -0.67945 0.3048)
			(end -0.120396 0.3048)
			(stroke
				(width 0.1)
				(type default)
			)
			(layer "B.Fab")
		)
		(fp_line
			(start -0.12065 -0.3048)
			(end -0.67945 -0.3048)
			(stroke
				(width 0.1)
				(type default)
			)
			(layer "B.Fab")
		)
		(fp_line
			(start -0.12065 -0.2794)
			(end -0.12065 -0.3048)
			(stroke
				(width 0.1)
				(type default)
			)
			(layer "B.Fab")
		)
		(fp_line
			(start -0.120396 0.2794)
			(end 0.12065 0.2794)
			(stroke
				(width 0.1)
				(type default)
			)
			(layer "B.Fab")
		)
		(fp_line
			(start -0.120396 0.3048)
			(end -0.120396 0.2794)
			(stroke
				(width 0.1)
				(type default)
			)
			(layer "B.Fab")
		)
		(fp_line
			(start 0.12065 -0.305054)
			(end 0.12065 -0.2794)
			(stroke
				(width 0.1)
				(type default)
			)
			(layer "B.Fab")
		)
		(fp_line
			(start 0.12065 -0.2794)
			(end -0.12065 -0.2794)
			(stroke
				(width 0.1)
				(type default)
			)
			(layer "B.Fab")
		)
		(fp_line
			(start 0.12065 0.2794)
			(end 0.12065 0.3048)
			(stroke
				(width 0.1)
				(type default)
			)
			(layer "B.Fab")
		)
		(fp_line
			(start 0.12065 0.3048)
			(end 0.67945 0.3048)
			(stroke
				(width 0.1)
				(type default)
			)
			(layer "B.Fab")
		)
		(fp_line
			(start 0.67945 -0.305054)
			(end 0.12065 -0.305054)
			(stroke
				(width 0.1)
				(type default)
			)
			(layer "B.Fab")
		)
		(fp_line
			(start 0.67945 0.3048)
			(end 0.67945 -0.305054)
			(stroke
				(width 0.1)
				(type default)
			)
			(layer "B.Fab")
		)
		(pad "1" smd circle
			(at 0.40005 0 180)
			(size 0 0)
			(layers "B.Cu" "B.Mask" "B.Paste")
			(net "PWRGD_PVDDCR_CPU0_P0_R")
		)
		(pad "2" smd circle
			(at -0.40005 0 180)
			(size 0 0)
			(layers "B.Cu" "B.Mask" "B.Paste")
			(net "GND")
		)
	)
)
